(kicad_pcb
	(version 20260206)
	(generator "pcbnew")
	(generator_version "10.0")
	(general
		(thickness 1.6)
		(legacy_teardrops no)
	)
	(paper "A4")
	(title_block
		(title "Bryce Canyon_F.DPB_16315-1-OCP.brd")
		(comment 1 "Bryce Canyon / footprints 1080-1086 of 2223")
	)
	(layers
		(0 "F.Cu" signal "TOP")
		(4 "In1.Cu" signal "L2GND")
		(6 "In2.Cu" signal "L3")
		(8 "In3.Cu" signal "L4GND")
		(10 "In4.Cu" signal "L5")
		(12 "In5.Cu" signal "L6VCC")
		(14 "In6.Cu" signal "L7VCC")
		(16 "In7.Cu" signal "L8")
		(18 "In8.Cu" signal "L9GND")
		(20 "In9.Cu" signal "L10")
		(22 "In10.Cu" signal "L11GND")
		(2 "B.Cu" signal "BOTTOM")
		(9 "F.Adhes" user "F.Adhesive")
		(11 "B.Adhes" user "B.Adhesive")
		(13 "F.Paste" user "Package Geometry/Pastemask Top")
		(15 "B.Paste" user "Package Geometry/Pastemask Bottom")
		(5 "F.SilkS" user "Ref Des/Silkscreen Top")
		(7 "B.SilkS" user "Ref Des/Silkscreen Bottom")
		(1 "F.Mask" user "Board Geometry/Soldermask Top")
		(3 "B.Mask" user "Board Geometry/Soldermask Bottom")
		(17 "Dwgs.User" user "User.Drawings")
		(19 "Cmts.User" user "User.Comments")
		(21 "Eco1.User" user "User.Eco1")
		(23 "Eco2.User" user "User.Eco2")
		(25 "Edge.Cuts" user "Board Geometry/Outline")
		(27 "Margin" user)
		(31 "F.CrtYd" user "Package Geometry/Place Bound Top")
		(29 "B.CrtYd" user "Package Geometry/Place Bound Bottom")
		(35 "F.Fab" user "Ref Des/Assembly Top")
		(33 "B.Fab" user "Ref Des/Assembly Bottom")
	)
	(footprint ""
		(layer "F.Cu")
		(at 65.936876 -304.385472 180)
		(property "Reference" "R230"
			(at 0 0 180)
			(layer "F.SilkS")
			(hide yes)
			(effects
				(font
					(size 1.27 1.27)
				)
			)
		)
		(property "Value" "91R3F-1-GP"
			(at -0.0254 -2.5146 180)
			(unlocked yes)
			(layer "F.Fab")
			(hide yes)
			(effects
				(font
					(size 1.016 1.016)
					(thickness 0.1524)
				)
			)
		)
		(property "Device Type" "R603H22"
			(at -0.0254 -4.0386 180)
			(unlocked yes)
			(layer "F.Fab")
			(hide yes)
			(effects
				(font
					(size 1.016 1.016)
					(thickness 0.1524)
				)
			)
		)
		(duplicate_pad_numbers_are_jumpers no)
		(fp_line
			(start 0.2032 0)
			(end 0.4826 0)
			(stroke
				(width 0.2032)
				(type default)
			)
			(layer "F.SilkS")
		)
		(fp_line
			(start -0.4826 0)
			(end -0.2032 0)
			(stroke
				(width 0.2032)
				(type default)
			)
			(layer "F.SilkS")
		)
		(fp_rect
			(start -0.5842 1.3335)
			(end 0.5842 -1.3335)
			(stroke
				(width 0)
				(type default)
			)
			(fill no)
			(layer "F.CrtYd")
		)
		(fp_rect
			(start -0.5842 1.3335)
			(end 0.5842 -1.3335)
			(stroke
				(width 0)
				(type default)
			)
			(fill no)
			(layer "F.Fab")
		)
		(pad "1" smd custom
			(at 0 -0.762 180)
			(size 0.2159 0.2159)
			(layers "F.Cu" "F.Mask" "F.Paste")
			(net "P5V_B")
			(options
				(clearance outline)
				(anchor circle)
			)
			(primitives
				(gr_poly
					(pts
						(arc
							(start -0.3302 -0.4318)
							(mid -0.402042 -0.402042)
							(end -0.4318 -0.3302)
						)
						(arc
							(start -0.4318 0.3302)
							(mid -0.402042 0.402042)
							(end -0.3302 0.4318)
						)
						(arc
							(start 0.3302 0.4318)
							(mid 0.402042 0.402042)
							(end 0.4318 0.3302)
						)
						(arc
							(start 0.4318 -0.3302)
							(mid 0.402042 -0.402042)
							(end 0.3302 -0.4318)
						)
					)
					(width 0)
					(fill yes)
				)
			)
		)
		(pad "2" smd custom
			(at 0 0.762 180)
			(size 0.2159 0.2159)
			(layers "F.Cu" "F.Mask" "F.Paste")
			(net "DRV_ACT_26")
			(options
				(clearance outline)
				(anchor circle)
			)
			(primitives
				(gr_poly
					(pts
						(arc
							(start -0.3302 -0.4318)
							(mid -0.402042 -0.402042)
							(end -0.4318 -0.3302)
						)
						(arc
							(start -0.4318 0.3302)
							(mid -0.402042 0.402042)
							(end -0.3302 0.4318)
						)
						(arc
							(start 0.3302 0.4318)
							(mid 0.402042 0.402042)
							(end 0.4318 0.3302)
						)
						(arc
							(start 0.4318 -0.3302)
							(mid 0.402042 -0.402042)
							(end 0.3302 -0.4318)
						)
					)
					(width 0)
					(fill yes)
				)
			)
		)
	)
	(footprint ""
		(layer "F.Cu")
		(at 444.4619 -291.127942 -90)
		(property "Reference" "C176"
			(at 0 0 270)
			(layer "F.SilkS")
			(hide yes)
			(effects
				(font
					(size 1.27 1.27)
				)
			)
		)
		(property "Value" "SCD01U50V2KX-1GP"
			(at 1.1811 -2.7051 270)
			(unlocked yes)
			(layer "F.Fab")
			(hide yes)
			(effects
				(font
					(size 1.016 1.016)
					(thickness 0.1524)
				)
			)
		)
		(property "Device Type" "C402H22"
			(at 1.1811 -4.2291 270)
			(unlocked yes)
			(layer "F.Fab")
			(hide yes)
			(effects
				(font
					(size 1.016 1.016)
					(thickness 0.1524)
				)
			)
		)
		(duplicate_pad_numbers_are_jumpers no)
		(fp_rect
			(start -0.4318 0.9525)
			(end 0.4318 -0.9525)
			(stroke
				(width 0)
				(type default)
			)
			(fill no)
			(layer "F.CrtYd")
		)
		(fp_rect
			(start -0.4318 0.9525)
			(end 0.4318 -0.9525)
			(stroke
				(width 0)
				(type default)
			)
			(fill no)
			(layer "F.Fab")
		)
		(pad "1" smd custom
			(at 0 -0.4445 270)
			(size 0.1524 0.1524)
			(layers "F.Cu" "F.Mask" "F.Paste")
			(net "HDD_PRSNT_10")
			(options
				(clearance outline)
				(anchor circle)
			)
			(primitives
				(gr_poly
					(pts
						(arc
							(start 0.3048 -0.2032)
							(mid 0.275042 -0.275042)
							(end 0.2032 -0.3048)
						)
						(arc
							(start -0.2032 -0.3048)
							(mid -0.275042 -0.275042)
							(end -0.3048 -0.2032)
						)
						(arc
							(start -0.3048 0.2032)
							(mid -0.275042 0.275042)
							(end -0.2032 0.3048)
						)
						(arc
							(start 0.2032 0.3048)
							(mid 0.275042 0.275042)
							(end 0.3048 0.2032)
						)
					)
					(width 0)
					(fill yes)
				)
			)
		)
		(pad "2" smd custom
			(at 0 0.4445 270)
			(size 0.1524 0.1524)
			(layers "F.Cu" "F.Mask" "F.Paste")
			(net "GND")
			(options
				(clearance outline)
				(anchor circle)
			)
			(primitives
				(gr_poly
					(pts
						(arc
							(start 0.3048 -0.2032)
							(mid 0.275042 -0.275042)
							(end 0.2032 -0.3048)
						)
						(arc
							(start -0.2032 -0.3048)
							(mid -0.275042 -0.275042)
							(end -0.3048 -0.2032)
						)
						(arc
							(start -0.3048 0.2032)
							(mid -0.275042 0.275042)
							(end -0.2032 0.3048)
						)
						(arc
							(start 0.2032 0.3048)
							(mid 0.275042 0.275042)
							(end 0.3048 0.2032)
						)
					)
					(width 0)
					(fill yes)
				)
			)
		)
	)
	(footprint ""
		(layer "F.Cu")
		(at 190.258954 -277.750016 -90)
		(property "Reference" "VIA44"
			(at 0 0 270)
			(layer "F.SilkS")
			(hide yes)
			(effects
				(font
					(size 1.27 1.27)
				)
			)
		)
		(property "Value" "100OHM-8L-1D6MM-L18L16-GP"
			(at -3.7211 -4.5085 270)
			(unlocked yes)
			(layer "F.Fab")
			(hide yes)
			(effects
				(font
					(size 1.016 1.016)
					(thickness 0.1524)
				)
			)
		)
		(property "Device Type" "VIA-PCIE-4P-394076"
			(at -3.7211 -6.0325 270)
			(unlocked yes)
			(layer "F.Fab")
			(hide yes)
			(effects
				(font
					(size 1.016 1.016)
					(thickness 0.1524)
				)
			)
		)
		(duplicate_pad_numbers_are_jumpers no)
		(fp_rect
			(start -1.9685 0.381)
			(end 1.9685 -0.381)
			(stroke
				(width 0)
				(type default)
			)
			(fill no)
			(layer "F.CrtYd")
		)
		(fp_rect
			(start -1.9685 0.381)
			(end 1.9685 -0.381)
			(stroke
				(width 0)
				(type default)
			)
			(fill no)
			(layer "F.Fab")
		)
		(pad "1" thru_hole circle
			(at -1.5875 0 270)
			(size 0.508 0.508)
			(drill 0.254)
			(layers "*.Cu" "*.Mask")
			(remove_unused_layers no)
			(net "GND")
			(clearance 0.127)
			(thermal_gap 0.127)
		)
		(pad "2" thru_hole circle
			(at -0.5715 0 270)
			(size 0.508 0.508)
			(drill 0.254)
			(layers "*.Cu" "*.Mask")
			(remove_unused_layers no)
			(net "PHY_DRV_A_TO_SCC_A_5_DP")
			(clearance 0.127)
			(thermal_gap 0.127)
		)
		(pad "3" thru_hole circle
			(at 0.5715 0 270)
			(size 0.508 0.508)
			(drill 0.254)
			(layers "*.Cu" "*.Mask")
			(remove_unused_layers no)
			(net "PHY_DRV_A_TO_SCC_A_5_DN")
			(clearance 0.127)
			(thermal_gap 0.127)
		)
		(pad "4" thru_hole circle
			(at 1.5875 0 270)
			(size 0.508 0.508)
			(drill 0.254)
			(layers "*.Cu" "*.Mask")
			(remove_unused_layers no)
			(net "GND")
			(clearance 0.127)
			(thermal_gap 0.127)
		)
	)
	(footprint ""
		(layer "F.Cu")
		(at 300.0502 -63.4492 90)
		(property "Reference" "R365"
			(at 0 0 90)
			(layer "F.SilkS")
			(hide yes)
			(effects
				(font
					(size 1.27 1.27)
				)
			)
		)
		(property "Value" "0R2J-2-GP"
			(at 0.064008 -3.993896 90)
			(unlocked yes)
			(layer "F.Fab")
			(hide yes)
			(effects
				(font
					(size 1.016 1.016)
					(thickness 0.1524)
				)
			)
		)
		(property "Device Type" "R402H16"
			(at 0.064008 -5.517896 90)
			(unlocked yes)
			(layer "F.Fab")
			(hide yes)
			(effects
				(font
					(size 1.016 1.016)
					(thickness 0.1524)
				)
			)
		)
		(duplicate_pad_numbers_are_jumpers no)
		(fp_line
			(start 0.508 -0.9398)
			(end -0.508 -0.9398)
			(stroke
				(width 0.1524)
				(type default)
			)
			(layer "F.SilkS")
		)
		(fp_line
			(start -0.508 -0.9398)
			(end -0.508 0.9398)
			(stroke
				(width 0.1524)
				(type default)
			)
			(layer "F.SilkS")
		)
		(fp_rect
			(start -0.508 0.9398)
			(end 0.508 -0.9398)
			(stroke
				(width 0)
				(type default)
			)
			(fill no)
			(layer "F.CrtYd")
		)
		(fp_rect
			(start -0.508 0.9398)
			(end 0.508 -0.9398)
			(stroke
				(width 0)
				(type default)
			)
			(fill no)
			(layer "F.Fab")
		)
		(pad "1" smd custom
			(at 0 -0.4445 90)
			(size 0.1397 0.1397)
			(layers "F.Cu" "F.Mask" "F.Paste")
			(net "I2C_BMC_B_COMP_B_SDA")
			(options
				(clearance outline)
				(anchor circle)
			)
			(primitives
				(gr_poly
					(pts
						(arc
							(start -0.1778 -0.2794)
							(mid -0.249642 -0.249642)
							(end -0.2794 -0.1778)
						)
						(arc
							(start -0.2794 0.1778)
							(mid -0.249642 0.249642)
							(end -0.1778 0.2794)
						)
						(arc
							(start 0.1778 0.2794)
							(mid 0.249642 0.249642)
							(end 0.2794 0.1778)
						)
						(arc
							(start 0.2794 -0.1778)
							(mid 0.249642 -0.249642)
							(end 0.1778 -0.2794)
						)
					)
					(width 0)
					(fill yes)
				)
			)
		)
		(pad "2" smd custom
			(at 0 0.4445 90)
			(size 0.1397 0.1397)
			(layers "F.Cu" "F.Mask" "F.Paste")
			(net "I2C_BMC_B_COMP_B_SDA_R")
			(options
				(clearance outline)
				(anchor circle)
			)
			(primitives
				(gr_poly
					(pts
						(arc
							(start -0.1778 -0.2794)
							(mid -0.249642 -0.249642)
							(end -0.2794 -0.1778)
						)
						(arc
							(start -0.2794 0.1778)
							(mid -0.249642 0.249642)
							(end -0.1778 0.2794)
						)
						(arc
							(start 0.1778 0.2794)
							(mid 0.249642 0.249642)
							(end 0.2794 0.1778)
						)
						(arc
							(start 0.2794 -0.1778)
							(mid 0.249642 -0.249642)
							(end 0.1778 -0.2794)
						)
					)
					(width 0)
					(fill yes)
				)
			)
		)
	)
	(footprint ""
		(layer "F.Cu")
		(at 172.466 -179.683918 -90)
		(property "Reference" "C265"
			(at 0 0 270)
			(layer "F.SilkS")
			(hide yes)
			(effects
				(font
					(size 1.27 1.27)
				)
			)
		)
		(property "Value" "SC4D7U25V5KX-1-GP"
			(at -0.0762 -6.1214 270)
			(unlocked yes)
			(layer "F.Fab")
			(hide yes)
			(effects
				(font
					(size 1.016 1.016)
					(thickness 0.1524)
				)
			)
		)
		(property "Device Type" "C805H58"
			(at -0.0762 -8.1534 270)
			(unlocked yes)
			(layer "F.Fab")
			(hide yes)
			(effects
				(font
					(size 1.016 1.016)
					(thickness 0.1524)
				)
			)
		)
		(duplicate_pad_numbers_are_jumpers no)
		(fp_line
			(start 0.635 0)
			(end -0.635 0)
			(stroke
				(width 0.508)
				(type default)
			)
			(layer "F.SilkS")
		)
		(fp_rect
			(start -0.9652 1.778)
			(end 0.9652 -1.778)
			(stroke
				(width 0)
				(type default)
			)
			(fill no)
			(layer "F.CrtYd")
		)
		(fp_poly
			(pts
				(xy -0.9652 -1.778) (xy 0.9652 -1.778) (xy 0.9652 1.778) (xy -0.9652 1.778)
			)
			(stroke
				(width 0)
				(type default)
			)
			(fill no)
			(layer "F.Fab")
		)
		(pad "1" smd rect
			(at 0 -0.9652 270)
			(size 1.397 1.143)
			(layers "F.Cu" "F.Mask" "F.Paste")
			(net "P12V_HDD17")
		)
		(pad "2" smd rect
			(at 0 0.9652 270)
			(size 1.397 1.143)
			(layers "F.Cu" "F.Mask" "F.Paste")
			(net "GND")
		)
	)
	(footprint ""
		(layer "F.Cu")
		(at 424.469052 -304.335942 180)
		(property "Reference" "C164"
			(at 0 0 180)
			(layer "F.SilkS")
			(hide yes)
			(effects
				(font
					(size 1.27 1.27)
				)
			)
		)
		(property "Value" "SC1U25V3KX-GP"
			(at 0 -2.8194 180)
			(unlocked yes)
			(layer "F.Fab")
			(hide yes)
			(effects
				(font
					(size 1.016 1.016)
					(thickness 0.1524)
				)
			)
		)
		(property "Device Type" "C603H36"
			(at 0 -4.3434 180)
			(unlocked yes)
			(layer "F.Fab")
			(hide yes)
			(effects
				(font
					(size 1.016 1.016)
					(thickness 0.1524)
				)
			)
		)
		(duplicate_pad_numbers_are_jumpers no)
		(fp_line
			(start 0.508 0)
			(end -0.508 0)
			(stroke
				(width 0.2032)
				(type default)
			)
			(layer "F.SilkS")
		)
		(fp_rect
			(start -0.5842 1.3335)
			(end 0.5842 -1.3335)
			(stroke
				(width 0)
				(type default)
			)
			(fill no)
			(layer "F.CrtYd")
		)
		(fp_rect
			(start -0.5842 1.3335)
			(end 0.5842 -1.3335)
			(stroke
				(width 0)
				(type default)
			)
			(fill no)
			(layer "F.Fab")
		)
		(pad "1" smd custom
			(at 0 -0.762 180)
			(size 0.2159 0.2159)
			(layers "F.Cu" "F.Mask" "F.Paste")
			(net "P12V_HDD9")
			(options
				(clearance outline)
				(anchor circle)
			)
			(primitives
				(gr_poly
					(pts
						(arc
							(start -0.3302 -0.4318)
							(mid -0.402042 -0.402042)
							(end -0.4318 -0.3302)
						)
						(arc
							(start -0.4318 0.3302)
							(mid -0.402042 0.402042)
							(end -0.3302 0.4318)
						)
						(arc
							(start 0.3302 0.4318)
							(mid 0.402042 0.402042)
							(end 0.4318 0.3302)
						)
						(arc
							(start 0.4318 -0.3302)
							(mid 0.402042 -0.402042)
							(end 0.3302 -0.4318)
						)
					)
					(width 0)
					(fill yes)
				)
			)
		)
		(pad "2" smd custom
			(at 0 0.762 180)
			(size 0.2159 0.2159)
			(layers "F.Cu" "F.Mask" "F.Paste")
			(net "GND")
			(options
				(clearance outline)
				(anchor circle)
			)
			(primitives
				(gr_poly
					(pts
						(arc
							(start -0.3302 -0.4318)
							(mid -0.402042 -0.402042)
							(end -0.4318 -0.3302)
						)
						(arc
							(start -0.4318 0.3302)
							(mid -0.402042 0.402042)
							(end -0.3302 0.4318)
						)
						(arc
							(start 0.3302 0.4318)
							(mid 0.402042 0.402042)
							(end 0.4318 0.3302)
						)
						(arc
							(start 0.4318 -0.3302)
							(mid 0.402042 -0.402042)
							(end 0.3302 -0.4318)
						)
					)
					(width 0)
					(fill yes)
				)
			)
		)
	)
	(footprint ""
		(layer "F.Cu")
		(at 244.86489 -381.013208)
		(property "Reference" "R142"
			(at 0 0 0)
			(layer "F.SilkS")
			(hide yes)
			(effects
				(font
					(size 1.27 1.27)
				)
			)
		)
		(property "Value" "0R5J-5-GP"
			(at 0 -8.9535 0)
			(unlocked yes)
			(layer "F.Fab")
			(hide yes)
			(effects
				(font
					(size 1.27 1.016)
					(thickness 0.1524)
				)
			)
		)
		(property "Device Type" "R805H24"
			(at 0 -10.6299 0)
			(unlocked yes)
			(layer "F.Fab")
			(hide yes)
			(effects
				(font
					(size 1.27 1.016)
					(thickness 0.1524)
				)
			)
		)
		(duplicate_pad_numbers_are_jumpers no)
		(fp_line
			(start -0.889 -1.7018)
			(end -0.889 0.2794)
			(stroke
				(width 0.1524)
				(type default)
			)
			(layer "F.SilkS")
		)
		(fp_line
			(start -0.889 0.0762)
			(end -0.889 1.7018)
			(stroke
				(width 0.1524)
				(type default)
			)
			(layer "F.SilkS")
		)
		(fp_line
			(start -0.889 1.7018)
			(end 0.889 1.7018)
			(stroke
				(width 0.1524)
				(type default)
			)
			(layer "F.SilkS")
		)
		(fp_line
			(start 0.889 -1.7018)
			(end -0.889 -1.7018)
			(stroke
				(width 0.1524)
				(type default)
			)
			(layer "F.SilkS")
		)
		(fp_line
			(start 0.889 -1.7018)
			(end 0.889 -0.381)
			(stroke
				(width 0.1524)
				(type default)
			)
			(layer "F.SilkS")
		)
		(fp_line
			(start 0.889 1.7018)
			(end 0.889 -0.508)
			(stroke
				(width 0.1524)
				(type default)
			)
			(layer "F.SilkS")
		)
		(fp_poly
			(pts
				(xy 0.9652 -1.778) (xy 0.9652 1.778) (xy -0.9652 1.778) (xy -0.9652 -1.778)
			)
			(stroke
				(width 0)
				(type default)
			)
			(fill no)
			(layer "F.CrtYd")
		)
		(fp_rect
			(start -0.9652 1.778)
			(end 0.9652 -1.778)
			(stroke
				(width 0)
				(type default)
			)
			(fill no)
			(layer "F.Fab")
		)
		(pad "1" smd rect
			(at 0 -0.9652)
			(size 1.397 1.143)
			(layers "F.Cu" "F.Mask" "F.Paste")
			(net "MB3_CM_GATE_R")
		)
		(pad "2" smd rect
			(at 0 0.9652)
			(size 1.397 1.143)
			(layers "F.Cu" "F.Mask" "F.Paste")
			(net "MB3_CM_GATE_C")
		)
	)
)
